# BASEBOARD_FAB2 (Tioga Pass) — schematic netlist excerpt (pin names and nets, part order shuffled) for the footprints in the layout excerpt that follows; sources: Cadence DE-HDL packaged netlist, KiCad conversion of Wiwynn_Tioga_Pass_MB.brd

C3M15  CAP  10UF 16V 10% X6S  pkg 0805  page 232 : A = VR_FET_SW_P12V_STBY_PVPP_DEF ; B = GND
C9N17  CAP  0.22UF 16V 10% X7R  pkg 0402  page 182 : A = P3E_CPU1_PE3_MP_C_TXP<8> ; B = P3E_CPU1_PE3_MP_TXP<8>
R25W15  120R2F-GP  1%  pkg RCL_GP  page 151 : \1\ = GND ; \2\ = BMC_M_A3

(kicad_pcb
	(version 20260206)
	(generator "pcbnew")
	(generator_version "10.0")
	(general
		(thickness 1.6)
		(legacy_teardrops no)
	)
	(paper "A4")
	(title_block
		(title "Wiwynn_Tioga_Pass_MB.brd")
		(comment 1 "Tioga Pass / footprints 4492-4494 of 4770")
	)
	(layers
		(0 "F.Cu" signal "TOP")
		(4 "In1.Cu" signal "L2GND")
		(6 "In2.Cu" signal "L3")
		(8 "In3.Cu" signal "L4GND")
		(10 "In4.Cu" signal "L5")
		(12 "In5.Cu" signal "L6GND")
		(14 "In6.Cu" signal "L7VCC")
		(16 "In7.Cu" signal "L8VCC")
		(18 "In8.Cu" signal "L9GND")
		(20 "In9.Cu" signal "L10")
		(22 "In10.Cu" signal "L11GND")
		(24 "In11.Cu" signal "L12")
		(26 "In12.Cu" signal "L13GND")
		(2 "B.Cu" signal "BOTTOM")
		(9 "F.Adhes" user "F.Adhesive")
		(11 "B.Adhes" user "B.Adhesive")
		(13 "F.Paste" user "Package Geometry/Pastemask Top")
		(15 "B.Paste" user "Package Geometry/Pastemask Bottom")
		(5 "F.SilkS" user "Ref Des/Silkscreen Top")
		(7 "B.SilkS" user "Ref Des/Silkscreen Bottom")
		(1 "F.Mask" user "Board Geometry/Soldermask Top")
		(3 "B.Mask" user "Board Geometry/Soldermask Bottom")
		(17 "Dwgs.User" user "User.Drawings")
		(19 "Cmts.User" user "User.Comments")
		(21 "Eco1.User" user "User.Eco1")
		(23 "Eco2.User" user "User.Eco2")
		(25 "Edge.Cuts" user "Board Geometry/Outline")
		(27 "Margin" user)
		(31 "F.CrtYd" user "Package Geometry/Place Bound Top")
		(29 "B.CrtYd" user "Package Geometry/Place Bound Bottom")
		(35 "F.Fab" user "Ref Des/Assembly Top")
		(33 "B.Fab" user "Ref Des/Assembly Bottom")
	)
	(footprint ""
		(layer "B.Cu")
		(at 13.11402 -97.99828 90)
		(property "Reference" "C9N17"
			(at 0 0 90)
			(layer "B.SilkS")
			(hide yes)
			(effects
				(font
					(size 1.27 1.27)
				)
				(justify mirror)
			)
		)
		(property "Value" ""
			(at 0 0 90)
			(layer "B.Fab")
			(effects
				(font
					(size 1.27 1.27)
				)
				(justify mirror)
			)
		)
		(duplicate_pad_numbers_are_jumpers no)
		(fp_poly
			(pts
				(xy -0.3048 -0.1016) (xy -0.3048 0.9906) (xy 0.3048 0.9906) (xy 0.3048 -0.1016)
			)
			(stroke
				(width 0)
				(type default)
			)
			(fill no)
			(layer "B.CrtYd")
		)
		(fp_line
			(start 0.3048 -0.1016)
			(end 0.3048 0.9906)
			(stroke
				(width 0.1)
				(type default)
			)
			(layer "B.Fab")
		)
		(fp_line
			(start -0.3048 -0.1016)
			(end 0.3048 -0.1016)
			(stroke
				(width 0.1)
				(type default)
			)
			(layer "B.Fab")
		)
		(fp_line
			(start 0.3048 0.9906)
			(end -0.3048 0.9906)
			(stroke
				(width 0.1)
				(type default)
			)
			(layer "B.Fab")
		)
		(fp_line
			(start -0.3048 0.9906)
			(end -0.3048 -0.1016)
			(stroke
				(width 0.1)
				(type default)
			)
			(layer "B.Fab")
		)
		(pad "1" smd rect
			(at 0 0 270)
			(size 0.508 0.508)
			(layers "B.Cu" "B.Mask" "B.Paste")
			(net "P3E_CPU1_PE3_MP_C_TXP<8>")
		)
		(pad "2" smd rect
			(at 0 0.889 270)
			(size 0.508 0.508)
			(layers "B.Cu" "B.Mask" "B.Paste")
			(net "P3E_CPU1_PE3_MP_TXP<8>")
		)
		(zone
			(layer "B.Cu")
			(hatch none 0.5)
			(connect_pads
				(clearance 0)
			)
			(min_thickness 0.25)
			(keepout
				(tracks allowed)
				(vias not_allowed)
				(pads allowed)
				(copperpour not_allowed)
				(footprints allowed)
			)
			(placement
				(enabled no)
				(sheetname "")
			)
			(fill
				(thermal_gap 0.5)
				(thermal_bridge_width 0.5)
				(island_removal_mode 0)
			)
			(polygon
				(pts
					(xy 13.36802 -98.25228) (xy 13.36802 -97.74428) (xy 13.74902 -97.74428) (xy 13.74902 -98.25228)
				)
			)
		)
		(zone
			(layer "B.Cu")
			(hatch none 0.5)
			(connect_pads
				(clearance 0)
			)
			(min_thickness 0.25)
			(keepout
				(tracks not_allowed)
				(vias allowed)
				(pads allowed)
				(copperpour not_allowed)
				(footprints allowed)
			)
			(placement
				(enabled no)
				(sheetname "")
			)
			(fill
				(thermal_gap 0.5)
				(thermal_bridge_width 0.5)
				(island_removal_mode 0)
			)
			(polygon
				(pts
					(xy 13.74902 -98.25228) (xy 13.74902 -97.74428) (xy 13.36802 -97.74428) (xy 13.36802 -98.25228)
				)
			)
		)
	)
	(footprint ""
		(layer "B.Cu")
		(at 439.976006 -41.648126 180)
		(property "Reference" "R25W15"
			(at 0 0 0)
			(layer "B.SilkS")
			(hide yes)
			(effects
				(font
					(size 1.27 1.27)
				)
				(justify mirror)
			)
		)
		(property "Value" "*"
			(at -0.064008 -4.108196 180)
			(unlocked yes)
			(layer "B.Fab")
			(hide yes)
			(effects
				(font
					(size 1.27 1.016)
					(thickness 0.1524)
				)
				(justify mirror)
			)
		)
		(property "Device Type" "120R2F-GP_RCL_GP-120R2F-GP,64.A"
			(at -0.064008 -5.632196 180)
			(unlocked yes)
			(layer "B.Fab")
			(hide yes)
			(effects
				(font
					(size 1.27 1.016)
					(thickness 0.1524)
				)
				(justify mirror)
			)
		)
		(duplicate_pad_numbers_are_jumpers no)
		(fp_line
			(start 0.508 -0.9398)
			(end 0.508 0.9398)
			(stroke
				(width 0.1524)
				(type default)
			)
			(layer "B.SilkS")
		)
		(fp_line
			(start -0.508 -0.9398)
			(end 0.508 -0.9398)
			(stroke
				(width 0.1524)
				(type default)
			)
			(layer "B.SilkS")
		)
		(fp_rect
			(start 0.508 0.9398)
			(end -0.508 -0.9398)
			(stroke
				(width 0)
				(type default)
			)
			(fill no)
			(layer "B.CrtYd")
		)
		(fp_rect
			(start 0.508 0.9398)
			(end -0.508 -0.9398)
			(stroke
				(width 0)
				(type default)
			)
			(fill no)
			(layer "B.Fab")
		)
		(pad "1" smd custom
			(at 0 -0.4445)
			(size 0.1397 0.1397)
			(layers "B.Cu" "B.Mask" "B.Paste")
			(net "GND")
			(options
				(clearance outline)
				(anchor circle)
			)
			(primitives
				(gr_poly
					(pts
						(arc
							(start -0.1778 0.2794)
							(mid -0.249642 0.249642)
							(end -0.2794 0.1778)
						)
						(arc
							(start -0.2794 -0.1778)
							(mid -0.249642 -0.249642)
							(end -0.1778 -0.2794)
						)
						(arc
							(start 0.1778 -0.2794)
							(mid 0.249642 -0.249642)
							(end 0.2794 -0.1778)
						)
						(arc
							(start 0.2794 0.1778)
							(mid 0.249642 0.249642)
							(end 0.1778 0.2794)
						)
					)
					(width 0)
					(fill yes)
				)
			)
		)
		(pad "2" smd custom
			(at 0 0.4445)
			(size 0.1397 0.1397)
			(layers "B.Cu" "B.Mask" "B.Paste")
			(net "BMC_M_A3")
			(options
				(clearance outline)
				(anchor circle)
			)
			(primitives
				(gr_poly
					(pts
						(arc
							(start -0.1778 0.2794)
							(mid -0.249642 0.249642)
							(end -0.2794 0.1778)
						)
						(arc
							(start -0.2794 -0.1778)
							(mid -0.249642 -0.249642)
							(end -0.1778 -0.2794)
						)
						(arc
							(start 0.1778 -0.2794)
							(mid 0.249642 -0.249642)
							(end 0.2794 -0.1778)
						)
						(arc
							(start 0.2794 0.1778)
							(mid 0.249642 0.249642)
							(end 0.1778 0.2794)
						)
					)
					(width 0)
					(fill yes)
				)
			)
		)
	)
	(footprint ""
		(layer "B.Cu")
		(at 346.814902 -133.133846 180)
		(property "Reference" "C3M15"
			(at 0 0 0)
			(layer "B.SilkS")
			(hide yes)
			(effects
				(font
					(size 1.27 1.27)
				)
				(justify mirror)
			)
		)
		(property "Value" ""
			(at 0 0 0)
			(layer "B.Fab")
			(effects
				(font
					(size 1.27 1.27)
				)
				(justify mirror)
			)
		)
		(duplicate_pad_numbers_are_jumpers no)
		(fp_poly
			(pts
				(xy 0.7239 -0.2159) (xy -0.7239 -0.2159) (xy -0.7239 1.9939) (xy 0.7239 1.9939)
			)
			(stroke
				(width 0)
				(type default)
			)
			(fill no)
			(layer "B.CrtYd")
		)
		(fp_line
			(start 0.7239 1.9939)
			(end -0.7239 1.9939)
			(stroke
				(width 0.1)
				(type default)
			)
			(layer "B.Fab")
		)
		(fp_line
			(start 0.7239 -0.2159)
			(end 0.7239 1.9939)
			(stroke
				(width 0.1)
				(type default)
			)
			(layer "B.Fab")
		)
		(fp_line
			(start -0.7239 1.9939)
			(end -0.7239 -0.2159)
			(stroke
				(width 0.1)
				(type default)
			)
			(layer "B.Fab")
		)
		(fp_line
			(start -0.7239 -0.2159)
			(end 0.7239 -0.2159)
			(stroke
				(width 0.1)
				(type default)
			)
			(layer "B.Fab")
		)
		(pad "1" smd rect
			(at 0 0)
			(size 1.27 1.016)
			(layers "B.Cu" "B.Mask" "B.Paste")
			(net "VR_FET_SW_P12V_STBY_PVPP_DEF")
		)
		(pad "2" smd rect
			(at 0 1.778)
			(size 1.27 1.016)
			(layers "B.Cu" "B.Mask" "B.Paste")
			(net "GND")
		)
		(zone
			(layer "B.Cu")
			(hatch none 0.5)
			(connect_pads
				(clearance 0)
			)
			(min_thickness 0.25)
			(keepout
				(tracks not_allowed)
				(vias allowed)
				(pads allowed)
				(copperpour not_allowed)
				(footprints allowed)
			)
			(placement
				(enabled no)
				(sheetname "")
			)
			(fill
				(thermal_gap 0.5)
				(thermal_bridge_width 0.5)
				(island_removal_mode 0)
			)
			(polygon
				(pts
					(xy 346.179902 -133.641846) (xy 347.449902 -133.641846) (xy 347.449902 -134.403846) (xy 346.179902 -134.403846)
				)
			)
		)
	)
)
